# TIMECARD (Time Appliance Project (Time Card)) — schematic netlist excerpt (pin names and nets, part order shuffled) for the footprints in the layout excerpt that follows; sources: Cadence DE-HDL packaged netlist, KiCad conversion of R4006-B0001-02_R01.brd

R312  RESISTOR  0OHM -  pkg SMC_0402R_H016  page 16 : \1\ = RGB_LED_I2C_SDA ; \2\ = EEPROM_SDA
C22  CAPACITOR  22UF 10V 20%  pkg SMC_0805R_H057  page 28 : \1\ = XP3R3V ; \2\ = SG

(kicad_pcb
	(version 20260206)
	(generator "pcbnew")
	(generator_version "10.0")
	(general
		(thickness 1.6)
		(legacy_teardrops no)
	)
	(paper "A4")
	(title_block
		(title "timecard-production-celestica-r4006 — R4006-B0001-02_R01.brd")
		(comment 1 "Time Appliance Project (Time Card) / footprints 254-255 of 1113")
	)
	(layers
		(0 "F.Cu" signal "TOP")
		(4 "In1.Cu" signal "L02_GND1")
		(6 "In2.Cu" signal "L03_SIG1")
		(8 "In3.Cu" signal "L04_GND2")
		(10 "In4.Cu" signal "L05_VCC1")
		(12 "In5.Cu" signal "L06_VCC2")
		(14 "In6.Cu" signal "L07_GND3")
		(16 "In7.Cu" signal "L08_SIG2")
		(18 "In8.Cu" signal "L09_GND4")
		(2 "B.Cu" signal "BOTTOM")
		(9 "F.Adhes" user "F.Adhesive")
		(11 "B.Adhes" user "B.Adhesive")
		(13 "F.Paste" user "Package Geometry/Pastemask Top")
		(15 "B.Paste" user "Package Geometry/Pastemask Bottom")
		(5 "F.SilkS" user "Ref Des/Silkscreen Top")
		(7 "B.SilkS" user "Ref Des/Silkscreen Bottom")
		(1 "F.Mask" user "Board Geometry/Soldermask Top")
		(3 "B.Mask" user "Board Geometry/Soldermask Bottom")
		(17 "Dwgs.User" user "User.Drawings")
		(19 "Cmts.User" user "User.Comments")
		(21 "Eco1.User" user "User.Eco1")
		(23 "Eco2.User" user "User.Eco2")
		(25 "Edge.Cuts" user "Board Geometry/Outline")
		(27 "Margin" user)
		(31 "F.CrtYd" user "Package Geometry/Place Bound Top")
		(29 "B.CrtYd" user "Package Geometry/Place Bound Bottom")
		(35 "F.Fab" user "Ref Des/Assembly Top")
		(33 "B.Fab" user "Ref Des/Assembly Bottom")
	)
	(footprint ""
		(layer "F.Cu")
		(at 33.7693 -16.7132 180)
		(property "Reference" "R312"
			(at -2.6543 -2.07137 0)
			(unlocked yes)
			(layer "F.SilkS")
			(effects
				(font
					(size 0.7874 0.5842)
					(thickness 0.1524)
				)
			)
		)
		(property "Value" "VAL*"
			(at 0.02032 2.13233 180)
			(unlocked yes)
			(layer "F.Fab")
			(hide yes)
			(effects
				(font
					(size 0.7874 0.5842)
					(thickness 0.1524)
				)
			)
		)
		(property "Device Type" "RESISTOR-G155-100R0-J0,0OHM,-"
			(at 0.008382 1.210564 180)
			(unlocked yes)
			(layer "F.Fab")
			(hide yes)
			(effects
				(font
					(size 0.7874 0.5842)
					(thickness 0.1524)
				)
			)
		)
		(property "User Part Number" "PARTNUM*"
			(at 0.02032 4.024884 180)
			(unlocked yes)
			(layer "Cmts.User")
			(hide yes)
			(effects
				(font
					(size 0.7874 0.5842)
					(thickness 0.1524)
				)
			)
		)
		(property "Tolerance" "TOL*"
			(at 0.044704 3.05435 180)
			(unlocked yes)
			(layer "Cmts.User")
			(hide yes)
			(effects
				(font
					(size 0.7874 0.5842)
					(thickness 0.1524)
				)
			)
		)
		(duplicate_pad_numbers_are_jumpers no)
		(fp_line
			(start 1.143 0.5588)
			(end 1.143 -0.5588)
			(stroke
				(width 0.1)
				(type default)
			)
			(layer "F.SilkS")
		)
		(fp_line
			(start 1.143 -0.5588)
			(end -1.143 -0.5588)
			(stroke
				(width 0.1)
				(type default)
			)
			(layer "F.SilkS")
		)
		(fp_line
			(start -1.143 0.5588)
			(end 1.143 0.5588)
			(stroke
				(width 0.1)
				(type default)
			)
			(layer "F.SilkS")
		)
		(fp_line
			(start -1.143 -0.5588)
			(end -1.143 0.5588)
			(stroke
				(width 0.1)
				(type default)
			)
			(layer "F.SilkS")
		)
		(fp_poly
			(pts
				(xy -1.143 0.5588) (xy 1.143 0.5588) (xy 1.143 -0.5588) (xy -1.143 -0.5588)
			)
			(stroke
				(width 0)
				(type default)
			)
			(fill no)
			(layer "F.CrtYd")
		)
		(fp_line
			(start 0.508 0.3048)
			(end 0.508 -0.3048)
			(stroke
				(width 0.1)
				(type default)
			)
			(layer "F.Fab")
		)
		(fp_line
			(start 0.508 -0.3048)
			(end -0.508 -0.3048)
			(stroke
				(width 0.1)
				(type default)
			)
			(layer "F.Fab")
		)
		(fp_line
			(start -0.508 0.3048)
			(end 0.508 0.3048)
			(stroke
				(width 0.1)
				(type default)
			)
			(layer "F.Fab")
		)
		(fp_line
			(start -0.508 -0.3048)
			(end -0.508 0.3048)
			(stroke
				(width 0.1)
				(type default)
			)
			(layer "F.Fab")
		)
		(pad "1" smd rect
			(at -0.5334 0 180)
			(size 0.7112 0.6096)
			(layers "F.Cu" "F.Mask" "F.Paste")
			(net "RGB_LED_I2C_SDA")
		)
		(pad "2" smd rect
			(at 0.5334 0 180)
			(size 0.7112 0.6096)
			(layers "F.Cu" "F.Mask" "F.Paste")
			(net "EEPROM_SDA")
		)
		(zone
			(layer "F.Cu")
			(hatch none 0.5)
			(connect_pads
				(clearance 0)
			)
			(min_thickness 0.25)
			(keepout
				(tracks allowed)
				(vias not_allowed)
				(pads allowed)
				(copperpour not_allowed)
				(footprints allowed)
			)
			(placement
				(enabled no)
				(sheetname "")
			)
			(fill
				(thermal_gap 0.5)
				(thermal_bridge_width 0.5)
				(island_removal_mode 0)
			)
			(polygon
				(pts
					(xy 33.8455 -17.018) (xy 33.6931 -17.018) (xy 33.6931 -16.4084) (xy 33.8455 -16.4084)
				)
			)
		)
		(zone
			(layer "F.Cu")
			(hatch none 0.5)
			(connect_pads
				(clearance 0)
			)
			(min_thickness 0.25)
			(keepout
				(tracks not_allowed)
				(vias allowed)
				(pads allowed)
				(copperpour not_allowed)
				(footprints allowed)
			)
			(placement
				(enabled no)
				(sheetname "")
			)
			(fill
				(thermal_gap 0.5)
				(thermal_bridge_width 0.5)
				(island_removal_mode 0)
			)
			(polygon
				(pts
					(xy 33.8455 -17.018) (xy 33.6931 -17.018) (xy 33.6931 -16.4084) (xy 33.8455 -16.4084)
				)
			)
		)
	)
	(footprint ""
		(layer "F.Cu")
		(at 86.36 -93.599 90)
		(property "Reference" "C22"
			(at -3.81 -4.78663 90)
			(unlocked yes)
			(layer "F.SilkS")
			(effects
				(font
					(size 0.7874 0.5842)
					(thickness 0.1524)
				)
			)
		)
		(property "Value" "VAL*"
			(at 0.0762 3.134106 90)
			(unlocked yes)
			(layer "F.Fab")
			(hide yes)
			(effects
				(font
					(size 0.7874 0.5842)
					(thickness 0.1524)
				)
			)
		)
		(property "Tolerance" "TOL*"
			(at 0.0762 4.048506 90)
			(unlocked yes)
			(layer "Cmts.User")
			(hide yes)
			(effects
				(font
					(size 0.7874 0.5842)
					(thickness 0.1524)
				)
			)
		)
		(property "User Part Number" "PARTNUM*"
			(at 0.1016 5.013706 90)
			(unlocked yes)
			(layer "Cmts.User")
			(hide yes)
			(effects
				(font
					(size 0.7874 0.5842)
					(thickness 0.1524)
				)
			)
		)
		(property "Device Type" "CAPACITOR-G107-0F226-CM,22UF,2A"
			(at 0.0508 2.194306 90)
			(unlocked yes)
			(layer "F.Fab")
			(hide yes)
			(effects
				(font
					(size 0.7874 0.5842)
					(thickness 0.1524)
				)
			)
		)
		(duplicate_pad_numbers_are_jumpers no)
		(fp_line
			(start 1.5748 -0.9398)
			(end -1.5748 -0.9398)
			(stroke
				(width 0.1)
				(type default)
			)
			(layer "F.SilkS")
		)
		(fp_line
			(start -1.5748 -0.9398)
			(end -1.5748 0.9398)
			(stroke
				(width 0.1)
				(type default)
			)
			(layer "F.SilkS")
		)
		(fp_line
			(start 1.5748 0.9398)
			(end 1.5748 -0.9398)
			(stroke
				(width 0.1)
				(type default)
			)
			(layer "F.SilkS")
		)
		(fp_line
			(start -1.5748 0.9398)
			(end 1.5748 0.9398)
			(stroke
				(width 0.1)
				(type default)
			)
			(layer "F.SilkS")
		)
		(fp_rect
			(start 1.5748 0.9398)
			(end -1.5748 -0.9398)
			(stroke
				(width 0)
				(type default)
			)
			(fill no)
			(layer "F.CrtYd")
		)
		(fp_line
			(start 1.016 -0.635)
			(end -1.016 -0.635)
			(stroke
				(width 0.1)
				(type default)
			)
			(layer "F.Fab")
		)
		(fp_line
			(start -1.016 -0.635)
			(end -1.016 0.635)
			(stroke
				(width 0.1)
				(type default)
			)
			(layer "F.Fab")
		)
		(fp_line
			(start 1.016 0.635)
			(end 1.016 -0.635)
			(stroke
				(width 0.1)
				(type default)
			)
			(layer "F.Fab")
		)
		(fp_line
			(start -1.016 0.635)
			(end 1.016 0.635)
			(stroke
				(width 0.1)
				(type default)
			)
			(layer "F.Fab")
		)
		(pad "1" smd rect
			(at -0.8382 0 90)
			(size 0.9652 1.3716)
			(layers "F.Cu" "F.Mask" "F.Paste")
			(net "XP3R3V")
		)
		(pad "2" smd rect
			(at 0.8382 0 90)
			(size 0.9652 1.3716)
			(layers "F.Cu" "F.Mask" "F.Paste")
			(net "SG")
		)
		(zone
			(layer "F.Cu")
			(hatch none 0.5)
			(connect_pads
				(clearance 0)
			)
			(min_thickness 0.25)
			(keepout
				(tracks allowed)
				(vias not_allowed)
				(pads allowed)
				(copperpour not_allowed)
				(footprints allowed)
			)
			(placement
				(enabled no)
				(sheetname "")
			)
			(fill
				(thermal_gap 0.5)
				(thermal_bridge_width 0.5)
				(island_removal_mode 0)
			)
			(polygon
				(pts
					(xy 86.995 -93.8276) (xy 85.725 -93.8276) (xy 85.725 -93.3704) (xy 86.995 -93.3704)
				)
			)
		)
	)
)
